FILE_TYPE = MULTI_PHYS_TABLE;

PART 'SW_PUSHBUTTON4P_12_G34_H2'

{========================================================================================}
:VALUE                      | PART_TYPE | MATERIAL | PART_NUMBER    = STANDARD | LIFECYCLE     | PART_NUMBER   | JEDEC_TYPE        | DESCRIPTION                       | MANUFTR | MANUF_PN              | RD_CMPLS_LVL | CMPLS_LVL | CLASS | DIP_SMD | FROM_PJ      | DATA                       | FP_ECN | EE_CHECK_LIST | PSL | PREFERENCE | CREATOR | CREATEDAY  | STATUS ;
{========================================================================================}
 'SW4S_DTSAM-63N-S-Q-T/R'   | 'SMLF'    | 'MECH'   | 'DHPDTSAM600'(!) = ''       | ''               | 'DHPDTSAM600' |'SW4S_DTSAM63N'| 'SWITCH TACT DTSAM-63N-S-Q-T/R'   | 'DIP'   | 'DTSAM-63N-S-Q-T/R'   | 'EU(V1)'     | ''        | 'IO'  | ''      | 'T2R-WADE'   | 'DIP_RD5P6AM_REVA.pdf'     | ''     | ''            | ''  | ''         | ''      | '20140306' | ''    
 'SW4S_DTSAM-63N-S-Q-T/R'   | 'SMLF'    | 'EMPTY'  | 'DHPDTSAM600'(!) = ''       | ''               | 'DHPDTSAM600' |'SW4S_DTSAM63N'| 'SWITCH TACT DTSAM-63N-S-Q-T/R'   | 'DIP'   | 'DTSAM-63N-S-Q-T/R'   | 'EU(V1)'     | ''        | 'IO'  | ''      | 'T2R-WADE'   | 'DIP_RD5P6AM_REVA.pdf'     | ''     | ''            | ''  | ''         | ''      | '20140306' | ''    
 'SW4S_DTSAM-63N/K-S-Q-T/R' | 'SMLF'    | 'MECH'   | 'DHPDTSAM601'(!) = ''       | ''               | 'DHPDTSAM601' |'SW4S_DTSAM63N'| 'SWITCH TACT DTSAM-63N/K-S-Q-T/R' | 'DIP'   | 'DTSAM-63N/K-S-Q-T/R' | 'EU(V1)'     | ''        | 'IO'  | ''      | 'T2R-WADE'   | 'DIP_RD5P6AM_REVA.pdf'     | ''     | ''            | ''  | ''         | ''      | '20140306' | ''    
 'SW4S_DTSAM-63N/K-S-Q-T/R' | 'SMLF'    | 'EMPTY'  | 'DHPDTSAM601'(!) = ''       | ''               | 'DHPDTSAM601' |'SW4S_DTSAM63N'| 'SWITCH TACT DTSAM-63N/K-S-Q-T/R' | 'DIP'   | 'DTSAM-63N/K-S-Q-T/R' | 'EU(V1)'     | ''        | 'IO'  | ''      | 'T2R-WADE'   | 'DIP_RD5P6AM_REVA.pdf'     | ''     | ''            | ''  | ''         | ''      | '20140306' | ''    
 'SW4S_TA2-31SQR4'          | 'SMLF'    | 'MECH'   | 'DHPTA231S00'(!) = ''       | ''               | 'DHPTA231S00' |'SW4S_TA2-31SQR4'| 'SWITCH PUSH BUTTON TA2-31SQR4'   | 'DIP'   | 'TA2-31SQR4'          | 'EP(V1)'     | ''        | 'IO'  | ''      | 'JBK-EUPHIE' | 'DIP_TA2-31SQR4_REVA3.pdf' | ''     | ''            | ''  | ''         | ''      | '20140502' | ''    
 'SW4S_TA2-31SQR4'          | 'SMLF'    | 'EMPTY'  | 'DHPTA231S00'(!) = ''       | ''               | 'DHPTA231S00' |'SW4S_TA2-31SQR4'| 'SWITCH PUSH BUTTON TA2-31SQR4'   | 'DIP'   | 'TA2-31SQR4'          | 'EP(V1)'     | ''        | 'IO'  | ''      | 'JBK-EUPHIE' | 'DIP_TA2-31SQR4_REVA3.pdf' | ''     | ''            | ''  | ''         | ''      | '20140502' | ''    

END_PART

END.

